(kicad_pcb
	(version 20260206)
	(generator "pcbnew")
	(generator_version "10.0")
	(general
		(thickness 1.6)
		(legacy_teardrops no)
	)
	(paper "A4")
	(title_block
		(title "Bryce Canyon_F.DPB_16315-1-OCP.brd")
		(comment 1 "Bryce Canyon / footprint 2079 of 2223 (IO1), pads 110-166 of 202")
	)
	(layers
		(0 "F.Cu" signal "TOP")
		(4 "In1.Cu" signal "L2GND")
		(6 "In2.Cu" signal "L3")
		(8 "In3.Cu" signal "L4GND")
		(10 "In4.Cu" signal "L5")
		(12 "In5.Cu" signal "L6VCC")
		(14 "In6.Cu" signal "L7VCC")
		(16 "In7.Cu" signal "L8")
		(18 "In8.Cu" signal "L9GND")
		(20 "In9.Cu" signal "L10")
		(22 "In10.Cu" signal "L11GND")
		(2 "B.Cu" signal "BOTTOM")
		(9 "F.Adhes" user "F.Adhesive")
		(11 "B.Adhes" user "B.Adhesive")
		(13 "F.Paste" user "Package Geometry/Pastemask Top")
		(15 "B.Paste" user "Package Geometry/Pastemask Bottom")
		(5 "F.SilkS" user "Ref Des/Silkscreen Top")
		(7 "B.SilkS" user "Ref Des/Silkscreen Bottom")
		(1 "F.Mask" user "Board Geometry/Soldermask Top")
		(3 "B.Mask" user "Board Geometry/Soldermask Bottom")
		(17 "Dwgs.User" user "User.Drawings")
		(19 "Cmts.User" user "User.Comments")
		(21 "Eco1.User" user "User.Eco1")
		(23 "Eco2.User" user "User.Eco2")
		(25 "Edge.Cuts" user "Board Geometry/Outline")
		(27 "Margin" user)
		(31 "F.CrtYd" user "Package Geometry/Place Bound Top")
		(29 "B.CrtYd" user "Package Geometry/Place Bound Bottom")
		(35 "F.Fab" user "Ref Des/Assembly Top")
		(33 "B.Fab" user "Ref Des/Assembly Bottom")
	)
	(footprint ""
		(layer "B.Cu")
		(at 143.34998 -30.550104 180)
		(property "Reference" "IO1"
			(at 0 0 0)
			(layer "B.SilkS")
			(hide yes)
			(effects
				(font
					(size 1.27 1.27)
				)
				(justify mirror)
			)
		)
		(property "Value" "DM-AMP-CONN200-13R-6-GP-01"
			(at 47.5488 -16.5862 180)
			(unlocked yes)
			(layer "B.Fab")
			(hide yes)
			(effects
				(font
					(size 1.016 1.016)
					(thickness 0.1524)
				)
				(justify mirror)
			)
		)
		(property "Device Type" "DMFIT-200P-384346H577-01"
			(at 47.5488 -18.1102 180)
			(unlocked yes)
			(layer "B.Fab")
			(hide yes)
			(effects
				(font
					(size 1.016 1.016)
					(thickness 0.1524)
				)
				(justify mirror)
			)
		)
		(duplicate_pad_numbers_are_jumpers no)
		(pad "G12" thru_hole circle
			(at 26.999946 -11.800078)
			(size 0.664718 0.664718)
			(drill 0.359918)
			(layers "*.Cu" "*.Mask")
			(remove_unused_layers no)
			(net "PCIE_COMP_A_TO_IOM_A_19_DN")
			(clearance 0.264414)
			(padstack
				(mode custom)
				(layer "In1.Cu"
					(shape circle)
					(size 0.664718 0.664718)
					(clearance 0.264414)
				)
				(layer "In2.Cu"
					(shape circle)
					(size 0.664718 0.664718)
					(clearance 0.264414)
				)
				(layer "In3.Cu"
					(shape circle)
					(size 0.664718 0.664718)
					(clearance 0.264414)
				)
				(layer "In4.Cu"
					(shape circle)
					(size 0.664718 0.664718)
					(clearance 0.264414)
				)
				(layer "In5.Cu"
					(shape circle)
					(size 0.664718 0.664718)
					(clearance 0.264414)
				)
				(layer "In6.Cu"
					(shape circle)
					(size 0.762 0.762)
					(clearance 0.1651)
				)
				(layer "In7.Cu"
					(shape circle)
					(size 0.762 0.762)
					(clearance 0.1651)
				)
				(layer "In8.Cu"
					(shape circle)
					(size 0.762 0.762)
					(clearance 0.1651)
				)
				(layer "In9.Cu"
					(shape circle)
					(size 0.762 0.762)
					(clearance 0.1651)
				)
				(layer "In10.Cu"
					(shape circle)
					(size 0.762 0.762)
					(clearance 0.1651)
				)
				(layer "B.Cu"
					(shape circle)
					(size 0.762 0.762)
					(thermal_gap 0.1651)
					(clearance 0.1651)
				)
			)
		)
		(pad "G13" thru_hole circle
			(at 28.800044 -10.80008)
			(size 0.664718 0.664718)
			(drill 0.359918)
			(layers "*.Cu" "*.Mask")
			(remove_unused_layers no)
			(net "PCIE_COMP_A_TO_IOM_A_20_DN")
			(clearance 0.264414)
			(padstack
				(mode custom)
				(layer "In1.Cu"
					(shape circle)
					(size 0.664718 0.664718)
					(clearance 0.264414)
				)
				(layer "In2.Cu"
					(shape circle)
					(size 0.664718 0.664718)
					(clearance 0.264414)
				)
				(layer "In3.Cu"
					(shape circle)
					(size 0.664718 0.664718)
					(clearance 0.264414)
				)
				(layer "In4.Cu"
					(shape circle)
					(size 0.664718 0.664718)
					(clearance 0.264414)
				)
				(layer "In5.Cu"
					(shape circle)
					(size 0.664718 0.664718)
					(clearance 0.264414)
				)
				(layer "In6.Cu"
					(shape circle)
					(size 0.762 0.762)
					(clearance 0.1651)
				)
				(layer "In7.Cu"
					(shape circle)
					(size 0.762 0.762)
					(clearance 0.1651)
				)
				(layer "In8.Cu"
					(shape circle)
					(size 0.762 0.762)
					(clearance 0.1651)
				)
				(layer "In9.Cu"
					(shape circle)
					(size 0.762 0.762)
					(clearance 0.1651)
				)
				(layer "In10.Cu"
					(shape circle)
					(size 0.762 0.762)
					(clearance 0.1651)
				)
				(layer "B.Cu"
					(shape circle)
					(size 0.762 0.762)
					(thermal_gap 0.1651)
					(clearance 0.1651)
				)
			)
		)
		(pad "G14" thru_hole circle
			(at 30.599888 -11.800078)
			(size 0.664718 0.664718)
			(drill 0.359918)
			(layers "*.Cu" "*.Mask")
			(remove_unused_layers no)
			(net "PCIE_COMP_A_TO_IOM_A_21_DN")
			(clearance 0.264414)
			(padstack
				(mode custom)
				(layer "In1.Cu"
					(shape circle)
					(size 0.664718 0.664718)
					(clearance 0.264414)
				)
				(layer "In2.Cu"
					(shape circle)
					(size 0.664718 0.664718)
					(clearance 0.264414)
				)
				(layer "In3.Cu"
					(shape circle)
					(size 0.664718 0.664718)
					(clearance 0.264414)
				)
				(layer "In4.Cu"
					(shape circle)
					(size 0.664718 0.664718)
					(clearance 0.264414)
				)
				(layer "In5.Cu"
					(shape circle)
					(size 0.664718 0.664718)
					(clearance 0.264414)
				)
				(layer "In6.Cu"
					(shape circle)
					(size 0.762 0.762)
					(clearance 0.1651)
				)
				(layer "In7.Cu"
					(shape circle)
					(size 0.762 0.762)
					(clearance 0.1651)
				)
				(layer "In8.Cu"
					(shape circle)
					(size 0.762 0.762)
					(clearance 0.1651)
				)
				(layer "In9.Cu"
					(shape circle)
					(size 0.762 0.762)
					(clearance 0.1651)
				)
				(layer "In10.Cu"
					(shape circle)
					(size 0.762 0.762)
					(clearance 0.1651)
				)
				(layer "B.Cu"
					(shape circle)
					(size 0.762 0.762)
					(thermal_gap 0.1651)
					(clearance 0.1651)
				)
			)
		)
		(pad "G15" thru_hole circle
			(at 32.399986 -10.80008)
			(size 0.664718 0.664718)
			(drill 0.359918)
			(layers "*.Cu" "*.Mask")
			(remove_unused_layers no)
			(net "PCIE_COMP_A_TO_IOM_A_22_DN")
			(clearance 0.264414)
			(padstack
				(mode custom)
				(layer "In1.Cu"
					(shape circle)
					(size 0.664718 0.664718)
					(clearance 0.264414)
				)
				(layer "In2.Cu"
					(shape circle)
					(size 0.664718 0.664718)
					(clearance 0.264414)
				)
				(layer "In3.Cu"
					(shape circle)
					(size 0.664718 0.664718)
					(clearance 0.264414)
				)
				(layer "In4.Cu"
					(shape circle)
					(size 0.664718 0.664718)
					(clearance 0.264414)
				)
				(layer "In5.Cu"
					(shape circle)
					(size 0.664718 0.664718)
					(clearance 0.264414)
				)
				(layer "In6.Cu"
					(shape circle)
					(size 0.762 0.762)
					(clearance 0.1651)
				)
				(layer "In7.Cu"
					(shape circle)
					(size 0.762 0.762)
					(clearance 0.1651)
				)
				(layer "In8.Cu"
					(shape circle)
					(size 0.762 0.762)
					(clearance 0.1651)
				)
				(layer "In9.Cu"
					(shape circle)
					(size 0.762 0.762)
					(clearance 0.1651)
				)
				(layer "In10.Cu"
					(shape circle)
					(size 0.762 0.762)
					(clearance 0.1651)
				)
				(layer "B.Cu"
					(shape circle)
					(size 0.762 0.762)
					(thermal_gap 0.1651)
					(clearance 0.1651)
				)
			)
		)
		(pad "G16" thru_hole circle
			(at 34.200084 -11.800078)
			(size 0.664718 0.664718)
			(drill 0.359918)
			(layers "*.Cu" "*.Mask")
			(remove_unused_layers no)
			(net "PCIE_COMP_A_TO_IOM_A_23_DN")
			(clearance 0.264414)
			(padstack
				(mode custom)
				(layer "In1.Cu"
					(shape circle)
					(size 0.664718 0.664718)
					(clearance 0.264414)
				)
				(layer "In2.Cu"
					(shape circle)
					(size 0.664718 0.664718)
					(clearance 0.264414)
				)
				(layer "In3.Cu"
					(shape circle)
					(size 0.664718 0.664718)
					(clearance 0.264414)
				)
				(layer "In4.Cu"
					(shape circle)
					(size 0.664718 0.664718)
					(clearance 0.264414)
				)
				(layer "In5.Cu"
					(shape circle)
					(size 0.664718 0.664718)
					(clearance 0.264414)
				)
				(layer "In6.Cu"
					(shape circle)
					(size 0.762 0.762)
					(clearance 0.1651)
				)
				(layer "In7.Cu"
					(shape circle)
					(size 0.762 0.762)
					(clearance 0.1651)
				)
				(layer "In8.Cu"
					(shape circle)
					(size 0.762 0.762)
					(clearance 0.1651)
				)
				(layer "In9.Cu"
					(shape circle)
					(size 0.762 0.762)
					(clearance 0.1651)
				)
				(layer "In10.Cu"
					(shape circle)
					(size 0.762 0.762)
					(clearance 0.1651)
				)
				(layer "B.Cu"
					(shape circle)
					(size 0.762 0.762)
					(thermal_gap 0.1651)
					(clearance 0.1651)
				)
			)
		)
		(pad "GND1" thru_hole circle
			(at 0 -2.500122)
			(size 0.762 0.762)
			(drill 0.359918)
			(layers "*.Cu" "*.Mask")
			(remove_unused_layers no)
			(net "GND")
			(clearance 0.1651)
			(thermal_gap 0.1651)
		)
		(pad "GND2" thru_hole circle
			(at 0 -6.100064)
			(size 0.762 0.762)
			(drill 0.359918)
			(layers "*.Cu" "*.Mask")
			(remove_unused_layers no)
			(net "GND")
			(clearance 0.1651)
			(thermal_gap 0.1651)
		)
		(pad "GND3" thru_hole circle
			(at 0 -9.700006)
			(size 0.762 0.762)
			(drill 0.359918)
			(layers "*.Cu" "*.Mask")
			(remove_unused_layers no)
			(net "GND")
			(clearance 0.1651)
			(thermal_gap 0.1651)
		)
		(pad "GND4" thru_hole circle
			(at 0 -13.299948)
			(size 0.762 0.762)
			(drill 0.359918)
			(layers "*.Cu" "*.Mask")
			(remove_unused_layers no)
			(net "GND")
			(clearance 0.1651)
			(thermal_gap 0.1651)
		)
		(pad "GND5" thru_hole circle
			(at 1.800098 0.100076)
			(size 0.762 0.762)
			(drill 0.359918)
			(layers "*.Cu" "*.Mask")
			(remove_unused_layers no)
			(net "GND")
			(clearance 0.1651)
			(thermal_gap 0.1651)
		)
		(pad "GND6" thru_hole circle
			(at 1.800098 -3.50012)
			(size 0.762 0.762)
			(drill 0.359918)
			(layers "*.Cu" "*.Mask")
			(remove_unused_layers no)
			(net "GND")
			(clearance 0.1651)
			(thermal_gap 0.1651)
		)
		(pad "GND7" thru_hole circle
			(at 1.800098 -7.100062)
			(size 0.762 0.762)
			(drill 0.359918)
			(layers "*.Cu" "*.Mask")
			(remove_unused_layers no)
			(net "GND")
			(clearance 0.1651)
			(thermal_gap 0.1651)
		)
		(pad "GND8" thru_hole circle
			(at 1.800098 -10.700004)
			(size 0.762 0.762)
			(drill 0.359918)
			(layers "*.Cu" "*.Mask")
			(remove_unused_layers no)
			(net "GND")
			(clearance 0.1651)
			(thermal_gap 0.1651)
		)
		(pad "GND9" thru_hole circle
			(at 1.800098 -14.299946)
			(size 0.762 0.762)
			(drill 0.359918)
			(layers "*.Cu" "*.Mask")
			(remove_unused_layers no)
			(net "GND")
			(clearance 0.1651)
			(thermal_gap 0.1651)
		)
		(pad "GND10" thru_hole circle
			(at 3.599942 -2.500122)
			(size 0.762 0.762)
			(drill 0.359918)
			(layers "*.Cu" "*.Mask")
			(remove_unused_layers no)
			(net "GND")
			(clearance 0.1651)
			(thermal_gap 0.1651)
		)
		(pad "GND11" thru_hole circle
			(at 3.599942 -6.100064)
			(size 0.762 0.762)
			(drill 0.359918)
			(layers "*.Cu" "*.Mask")
			(remove_unused_layers no)
			(net "GND")
			(clearance 0.1651)
			(thermal_gap 0.1651)
		)
		(pad "GND12" thru_hole circle
			(at 3.599942 -9.700006)
			(size 0.762 0.762)
			(drill 0.359918)
			(layers "*.Cu" "*.Mask")
			(remove_unused_layers no)
			(net "GND")
			(clearance 0.1651)
			(thermal_gap 0.1651)
		)
		(pad "GND13" thru_hole circle
			(at 3.599942 -13.299948)
			(size 0.762 0.762)
			(drill 0.359918)
			(layers "*.Cu" "*.Mask")
			(remove_unused_layers no)
			(net "GND")
			(clearance 0.1651)
			(thermal_gap 0.1651)
		)
		(pad "GND14" thru_hole circle
			(at 5.40004 0.100076)
			(size 0.762 0.762)
			(drill 0.359918)
			(layers "*.Cu" "*.Mask")
			(remove_unused_layers no)
			(net "GND")
			(clearance 0.1651)
			(thermal_gap 0.1651)
		)
		(pad "GND15" thru_hole circle
			(at 5.40004 -3.50012)
			(size 0.762 0.762)
			(drill 0.359918)
			(layers "*.Cu" "*.Mask")
			(remove_unused_layers no)
			(net "GND")
			(clearance 0.1651)
			(thermal_gap 0.1651)
		)
		(pad "GND16" thru_hole circle
			(at 5.40004 -7.100062)
			(size 0.762 0.762)
			(drill 0.359918)
			(layers "*.Cu" "*.Mask")
			(remove_unused_layers no)
			(net "GND")
			(clearance 0.1651)
			(thermal_gap 0.1651)
		)
		(pad "GND17" thru_hole circle
			(at 5.40004 -10.700004)
			(size 0.762 0.762)
			(drill 0.359918)
			(layers "*.Cu" "*.Mask")
			(remove_unused_layers no)
			(net "GND")
			(clearance 0.1651)
			(thermal_gap 0.1651)
		)
		(pad "GND18" thru_hole circle
			(at 5.40004 -14.299946)
			(size 0.762 0.762)
			(drill 0.359918)
			(layers "*.Cu" "*.Mask")
			(remove_unused_layers no)
			(net "GND")
			(clearance 0.1651)
			(thermal_gap 0.1651)
		)
		(pad "GND19" thru_hole circle
			(at 7.199884 -2.500122)
			(size 0.762 0.762)
			(drill 0.359918)
			(layers "*.Cu" "*.Mask")
			(remove_unused_layers no)
			(net "GND")
			(clearance 0.1651)
			(thermal_gap 0.1651)
		)
		(pad "GND20" thru_hole circle
			(at 7.199884 -6.100064)
			(size 0.762 0.762)
			(drill 0.359918)
			(layers "*.Cu" "*.Mask")
			(remove_unused_layers no)
			(net "GND")
			(clearance 0.1651)
			(thermal_gap 0.1651)
		)
		(pad "GND21" thru_hole circle
			(at 7.199884 -9.700006)
			(size 0.762 0.762)
			(drill 0.359918)
			(layers "*.Cu" "*.Mask")
			(remove_unused_layers no)
			(net "GND")
			(clearance 0.1651)
			(thermal_gap 0.1651)
		)
		(pad "GND22" thru_hole circle
			(at 7.199884 -13.299948)
			(size 0.762 0.762)
			(drill 0.359918)
			(layers "*.Cu" "*.Mask")
			(remove_unused_layers no)
			(net "GND")
			(clearance 0.1651)
			(thermal_gap 0.1651)
		)
		(pad "GND23" thru_hole circle
			(at 8.999982 0.100076)
			(size 0.762 0.762)
			(drill 0.359918)
			(layers "*.Cu" "*.Mask")
			(remove_unused_layers no)
			(net "GND")
			(clearance 0.1651)
			(thermal_gap 0.1651)
		)
		(pad "GND24" thru_hole circle
			(at 8.999982 -3.50012)
			(size 0.762 0.762)
			(drill 0.359918)
			(layers "*.Cu" "*.Mask")
			(remove_unused_layers no)
			(net "GND")
			(clearance 0.1651)
			(thermal_gap 0.1651)
		)
		(pad "GND25" thru_hole circle
			(at 8.999982 -7.100062)
			(size 0.762 0.762)
			(drill 0.359918)
			(layers "*.Cu" "*.Mask")
			(remove_unused_layers no)
			(net "GND")
			(clearance 0.1651)
			(thermal_gap 0.1651)
		)
		(pad "GND26" thru_hole circle
			(at 8.999982 -10.700004)
			(size 0.762 0.762)
			(drill 0.359918)
			(layers "*.Cu" "*.Mask")
			(remove_unused_layers no)
			(net "GND")
			(clearance 0.1651)
			(thermal_gap 0.1651)
		)
		(pad "GND27" thru_hole circle
			(at 8.999982 -14.299946)
			(size 0.762 0.762)
			(drill 0.359918)
			(layers "*.Cu" "*.Mask")
			(remove_unused_layers no)
			(net "GND")
			(clearance 0.1651)
			(thermal_gap 0.1651)
		)
		(pad "GND28" thru_hole circle
			(at 10.80008 -2.500122)
			(size 0.762 0.762)
			(drill 0.359918)
			(layers "*.Cu" "*.Mask")
			(remove_unused_layers no)
			(net "GND")
			(clearance 0.1651)
			(thermal_gap 0.1651)
		)
		(pad "GND29" thru_hole circle
			(at 10.80008 -6.100064)
			(size 0.762 0.762)
			(drill 0.359918)
			(layers "*.Cu" "*.Mask")
			(remove_unused_layers no)
			(net "GND")
			(clearance 0.1651)
			(thermal_gap 0.1651)
		)
		(pad "GND30" thru_hole circle
			(at 10.80008 -9.700006)
			(size 0.762 0.762)
			(drill 0.359918)
			(layers "*.Cu" "*.Mask")
			(remove_unused_layers no)
			(net "GND")
			(clearance 0.1651)
			(thermal_gap 0.1651)
		)
		(pad "GND31" thru_hole circle
			(at 10.80008 -13.299948)
			(size 0.762 0.762)
			(drill 0.359918)
			(layers "*.Cu" "*.Mask")
			(remove_unused_layers no)
			(net "GND")
			(clearance 0.1651)
			(thermal_gap 0.1651)
		)
		(pad "GND32" thru_hole circle
			(at 12.599924 0.100076)
			(size 0.762 0.762)
			(drill 0.359918)
			(layers "*.Cu" "*.Mask")
			(remove_unused_layers no)
			(net "GND")
			(clearance 0.1651)
			(thermal_gap 0.1651)
		)
		(pad "GND33" thru_hole circle
			(at 12.599924 -3.50012)
			(size 0.762 0.762)
			(drill 0.359918)
			(layers "*.Cu" "*.Mask")
			(remove_unused_layers no)
			(net "GND")
			(clearance 0.1651)
			(thermal_gap 0.1651)
		)
		(pad "GND34" thru_hole circle
			(at 12.599924 -7.100062)
			(size 0.762 0.762)
			(drill 0.359918)
			(layers "*.Cu" "*.Mask")
			(remove_unused_layers no)
			(net "GND")
			(clearance 0.1651)
			(thermal_gap 0.1651)
		)
		(pad "GND35" thru_hole circle
			(at 12.599924 -10.700004)
			(size 0.762 0.762)
			(drill 0.359918)
			(layers "*.Cu" "*.Mask")
			(remove_unused_layers no)
			(net "GND")
			(clearance 0.1651)
			(thermal_gap 0.1651)
		)
		(pad "GND36" thru_hole circle
			(at 12.599924 -14.299946)
			(size 0.762 0.762)
			(drill 0.359918)
			(layers "*.Cu" "*.Mask")
			(remove_unused_layers no)
			(net "GND")
			(clearance 0.1651)
			(thermal_gap 0.1651)
		)
		(pad "GND37" thru_hole circle
			(at 21.599906 -2.500122)
			(size 0.762 0.762)
			(drill 0.359918)
			(layers "*.Cu" "*.Mask")
			(remove_unused_layers no)
			(net "GND")
			(clearance 0.1651)
			(thermal_gap 0.1651)
		)
		(pad "GND38" thru_hole circle
			(at 21.599906 -6.100064)
			(size 0.762 0.762)
			(drill 0.359918)
			(layers "*.Cu" "*.Mask")
			(remove_unused_layers no)
			(net "GND")
			(clearance 0.1651)
			(thermal_gap 0.1651)
		)
		(pad "GND39" thru_hole circle
			(at 21.599906 -9.700006)
			(size 0.762 0.762)
			(drill 0.359918)
			(layers "*.Cu" "*.Mask")
			(remove_unused_layers no)
			(net "GND")
			(clearance 0.1651)
			(thermal_gap 0.1651)
		)
		(pad "GND40" thru_hole circle
			(at 21.599906 -13.299948)
			(size 0.762 0.762)
			(drill 0.359918)
			(layers "*.Cu" "*.Mask")
			(remove_unused_layers no)
			(net "GND")
			(clearance 0.1651)
			(thermal_gap 0.1651)
		)
		(pad "GND41" thru_hole circle
			(at 23.400004 0.100076)
			(size 0.762 0.762)
			(drill 0.359918)
			(layers "*.Cu" "*.Mask")
			(remove_unused_layers no)
			(net "GND")
			(clearance 0.1651)
			(thermal_gap 0.1651)
		)
		(pad "GND42" thru_hole circle
			(at 23.400004 -3.50012)
			(size 0.762 0.762)
			(drill 0.359918)
			(layers "*.Cu" "*.Mask")
			(remove_unused_layers no)
			(net "GND")
			(clearance 0.1651)
			(thermal_gap 0.1651)
		)
		(pad "GND43" thru_hole circle
			(at 23.400004 -7.100062)
			(size 0.762 0.762)
			(drill 0.359918)
			(layers "*.Cu" "*.Mask")
			(remove_unused_layers no)
			(net "GND")
			(clearance 0.1651)
			(thermal_gap 0.1651)
		)
		(pad "GND44" thru_hole circle
			(at 23.400004 -10.700004)
			(size 0.762 0.762)
			(drill 0.359918)
			(layers "*.Cu" "*.Mask")
			(remove_unused_layers no)
			(net "GND")
			(clearance 0.1651)
			(thermal_gap 0.1651)
		)
		(pad "GND45" thru_hole circle
			(at 23.400004 -14.299946)
			(size 0.762 0.762)
			(drill 0.359918)
			(layers "*.Cu" "*.Mask")
			(remove_unused_layers no)
			(net "GND")
			(clearance 0.1651)
			(thermal_gap 0.1651)
		)
		(pad "GND46" thru_hole circle
			(at 25.200102 -2.500122)
			(size 0.762 0.762)
			(drill 0.359918)
			(layers "*.Cu" "*.Mask")
			(remove_unused_layers no)
			(net "GND")
			(clearance 0.1651)
			(thermal_gap 0.1651)
		)
		(pad "GND47" thru_hole circle
			(at 25.200102 -6.100064)
			(size 0.762 0.762)
			(drill 0.359918)
			(layers "*.Cu" "*.Mask")
			(remove_unused_layers no)
			(net "GND")
			(clearance 0.1651)
			(thermal_gap 0.1651)
		)
		(pad "GND48" thru_hole circle
			(at 25.200102 -9.700006)
			(size 0.762 0.762)
			(drill 0.359918)
			(layers "*.Cu" "*.Mask")
			(remove_unused_layers no)
			(net "GND")
			(clearance 0.1651)
			(thermal_gap 0.1651)
		)
		(pad "GND49" thru_hole circle
			(at 25.200102 -13.299948)
			(size 0.762 0.762)
			(drill 0.359918)
			(layers "*.Cu" "*.Mask")
			(remove_unused_layers no)
			(net "GND")
			(clearance 0.1651)
			(thermal_gap 0.1651)
		)
		(pad "GND50" thru_hole circle
			(at 26.999946 0.100076)
			(size 0.762 0.762)
			(drill 0.359918)
			(layers "*.Cu" "*.Mask")
			(remove_unused_layers no)
			(net "GND")
			(clearance 0.1651)
			(thermal_gap 0.1651)
		)
		(pad "GND51" thru_hole circle
			(at 26.999946 -3.50012)
			(size 0.762 0.762)
			(drill 0.359918)
			(layers "*.Cu" "*.Mask")
			(remove_unused_layers no)
			(net "GND")
			(clearance 0.1651)
			(thermal_gap 0.1651)
		)
		(pad "GND52" thru_hole circle
			(at 26.999946 -7.100062)
			(size 0.762 0.762)
			(drill 0.359918)
			(layers "*.Cu" "*.Mask")
			(remove_unused_layers no)
			(net "GND")
			(clearance 0.1651)
			(thermal_gap 0.1651)
		)
	)
)
